# T6G (Grand Teton) — schematic netlist excerpt (pin names and nets, part order shuffled) for the footprints in the layout excerpt that follows; sources: Cadence DE-HDL packaged netlist, KiCad conversion of 04192023_DAF0TMB3IC0_F0TG_MB_C_brd_V02_OCP.brd

C8016  Q_CAP  100NF 50V 10% EMPTY  pkg C0402  page 267 : A = P12V_AUX ; B = GND
C2658  Q_CAP  22UF 4V 20% X6S  pkg C0402  page 70 : A = PVDD11_S3_P0 ; B = GND
C189  Q_CAP  0.1UF 10V 10% X7S  pkg C0201  page 323 : A = P0V9_CPU1_RT_2D ; B = GND

(kicad_pcb
	(version 20260206)
	(generator "pcbnew")
	(generator_version "10.0")
	(general
		(thickness 1.6)
		(legacy_teardrops no)
	)
	(paper "A4")
	(title_block
		(title "04192023_DAF0TMB3IC0_F0TG_MB_C_brd_V02_OCP.brd")
		(comment 1 "Grand Teton / footprints 8125-8127 of 8354")
	)
	(layers
		(0 "F.Cu" signal "TOP")
		(4 "In1.Cu" signal "GND")
		(6 "In2.Cu" signal "IN1")
		(8 "In3.Cu" signal "GND1")
		(10 "In4.Cu" signal "IN2")
		(12 "In5.Cu" signal "GND2")
		(14 "In6.Cu" signal "IN3")
		(16 "In7.Cu" signal "GND3")
		(18 "In8.Cu" signal "VCC")
		(20 "In9.Cu" signal "VCC1")
		(22 "In10.Cu" signal "GND4")
		(24 "In11.Cu" signal "IN4")
		(26 "In12.Cu" signal "GND5")
		(28 "In13.Cu" signal "IN5")
		(30 "In14.Cu" signal "GND6")
		(32 "In15.Cu" signal "IN6")
		(34 "In16.Cu" signal "GND7")
		(2 "B.Cu" signal "BOTTOM")
		(9 "F.Adhes" user "F.Adhesive")
		(11 "B.Adhes" user "B.Adhesive")
		(13 "F.Paste" user "Package Geometry/Pastemask Top")
		(15 "B.Paste" user "Package Geometry/Pastemask Bottom")
		(5 "F.SilkS" user "Ref Des/Silkscreen Top")
		(7 "B.SilkS" user "Ref Des/Silkscreen Bottom")
		(1 "F.Mask" user "Board Geometry/Soldermask Top")
		(3 "B.Mask" user "Board Geometry/Soldermask Bottom")
		(17 "Dwgs.User" user "User.Drawings")
		(19 "Cmts.User" user "User.Comments")
		(21 "Eco1.User" user "User.Eco1")
		(23 "Eco2.User" user "User.Eco2")
		(25 "Edge.Cuts" user "Board Geometry/Outline")
		(27 "Margin" user)
		(31 "F.CrtYd" user "Package Geometry/Place Bound Top")
		(29 "B.CrtYd" user "Package Geometry/Place Bound Bottom")
		(35 "F.Fab" user "Ref Des/Assembly Top")
		(33 "B.Fab" user "Ref Des/Assembly Bottom")
	)
	(footprint ""
		(layer "B.Cu")
		(at 361.317032 -261.747762 90)
		(property "Reference" "C2658"
			(at 0 0 90)
			(layer "B.SilkS")
			(hide yes)
			(effects
				(font
					(size 1.27 1.27)
				)
				(justify mirror)
			)
		)
		(property "Value" ""
			(at 0 0 90)
			(layer "B.Fab")
			(effects
				(font
					(size 1.27 1.27)
				)
				(justify mirror)
			)
		)
		(duplicate_pad_numbers_are_jumpers no)
		(fp_line
			(start 0.7874 -0.4064)
			(end -0.7874 -0.4064)
			(stroke
				(width 0.1524)
				(type default)
			)
			(layer "B.SilkS")
		)
		(fp_line
			(start -0.7874 -0.4064)
			(end -0.7874 0.4064)
			(stroke
				(width 0.1524)
				(type default)
			)
			(layer "B.SilkS")
		)
		(fp_line
			(start 0.7874 0.4064)
			(end 0.7874 -0.4064)
			(stroke
				(width 0.1524)
				(type default)
			)
			(layer "B.SilkS")
		)
		(fp_line
			(start -0.7874 0.4064)
			(end 0.7874 0.4064)
			(stroke
				(width 0.1524)
				(type default)
			)
			(layer "B.SilkS")
		)
		(fp_line
			(start 0.67945 -0.305054)
			(end 0.12065 -0.305054)
			(stroke
				(width 0.1)
				(type default)
			)
			(layer "B.Fab")
		)
		(fp_line
			(start 0.12065 -0.305054)
			(end 0.12065 -0.2794)
			(stroke
				(width 0.1)
				(type default)
			)
			(layer "B.Fab")
		)
		(fp_line
			(start -0.12065 -0.3048)
			(end -0.67945 -0.3048)
			(stroke
				(width 0.1)
				(type default)
			)
			(layer "B.Fab")
		)
		(fp_line
			(start -0.67945 -0.3048)
			(end -0.67945 0.3048)
			(stroke
				(width 0.1)
				(type default)
			)
			(layer "B.Fab")
		)
		(fp_line
			(start 0.12065 -0.2794)
			(end -0.12065 -0.2794)
			(stroke
				(width 0.1)
				(type default)
			)
			(layer "B.Fab")
		)
		(fp_line
			(start -0.12065 -0.2794)
			(end -0.12065 -0.3048)
			(stroke
				(width 0.1)
				(type default)
			)
			(layer "B.Fab")
		)
		(fp_line
			(start 0.12065 0.2794)
			(end 0.12065 0.3048)
			(stroke
				(width 0.1)
				(type default)
			)
			(layer "B.Fab")
		)
		(fp_line
			(start -0.120396 0.2794)
			(end 0.12065 0.2794)
			(stroke
				(width 0.1)
				(type default)
			)
			(layer "B.Fab")
		)
		(fp_line
			(start 0.67945 0.3048)
			(end 0.67945 -0.305054)
			(stroke
				(width 0.1)
				(type default)
			)
			(layer "B.Fab")
		)
		(fp_line
			(start 0.12065 0.3048)
			(end 0.67945 0.3048)
			(stroke
				(width 0.1)
				(type default)
			)
			(layer "B.Fab")
		)
		(fp_line
			(start -0.120396 0.3048)
			(end -0.120396 0.2794)
			(stroke
				(width 0.1)
				(type default)
			)
			(layer "B.Fab")
		)
		(fp_line
			(start -0.67945 0.3048)
			(end -0.120396 0.3048)
			(stroke
				(width 0.1)
				(type default)
			)
			(layer "B.Fab")
		)
		(pad "1" smd circle
			(at 0.40005 0 270)
			(size 0 0)
			(layers "B.Cu" "B.Mask" "B.Paste")
			(net "PVDD11_S3_P0")
		)
		(pad "2" smd circle
			(at -0.40005 0 270)
			(size 0 0)
			(layers "B.Cu" "B.Mask" "B.Paste")
			(net "GND")
		)
	)
	(footprint ""
		(layer "B.Cu")
		(at 53.518562 -388.011162 -90)
		(property "Reference" "C189"
			(at 0 0 90)
			(layer "B.SilkS")
			(hide yes)
			(effects
				(font
					(size 1.27 1.27)
				)
				(justify mirror)
			)
		)
		(property "Value" ""
			(at 0 0 90)
			(layer "B.Fab")
			(effects
				(font
					(size 1.27 1.27)
				)
				(justify mirror)
			)
		)
		(duplicate_pad_numbers_are_jumpers no)
		(fp_line
			(start -0.299974 0.150114)
			(end 0.299974 0.150114)
			(stroke
				(width 0.1)
				(type default)
			)
			(layer "B.Fab")
		)
		(fp_line
			(start 0.299974 0.150114)
			(end 0.299974 -0.150114)
			(stroke
				(width 0.1)
				(type default)
			)
			(layer "B.Fab")
		)
		(fp_line
			(start -0.299974 -0.150114)
			(end -0.299974 0.150114)
			(stroke
				(width 0.1)
				(type default)
			)
			(layer "B.Fab")
		)
		(fp_line
			(start 0.299974 -0.150114)
			(end -0.299974 -0.150114)
			(stroke
				(width 0.1)
				(type default)
			)
			(layer "B.Fab")
		)
		(pad "1" smd rect
			(at 0.2667 0 90)
			(size 0.3048 0.381)
			(layers "B.Cu" "B.Mask" "B.Paste")
			(net "P0V9_CPU1_RT_2D")
		)
		(pad "2" smd rect
			(at -0.2667 0 90)
			(size 0.3048 0.381)
			(layers "B.Cu" "B.Mask" "B.Paste")
			(net "GND")
		)
	)
	(footprint ""
		(layer "B.Cu")
		(at 187.890404 -428.965106)
		(property "Reference" "C8016"
			(at 0 0 0)
			(layer "B.SilkS")
			(hide yes)
			(effects
				(font
					(size 1.27 1.27)
				)
				(justify mirror)
			)
		)
		(property "Value" ""
			(at 0 0 0)
			(layer "B.Fab")
			(effects
				(font
					(size 1.27 1.27)
				)
				(justify mirror)
			)
		)
		(duplicate_pad_numbers_are_jumpers no)
		(fp_line
			(start -0.7874 -0.4064)
			(end -0.7874 0.4064)
			(stroke
				(width 0.1524)
				(type default)
			)
			(layer "B.SilkS")
		)
		(fp_line
			(start -0.7874 0.4064)
			(end 0.7874 0.4064)
			(stroke
				(width 0.1524)
				(type default)
			)
			(layer "B.SilkS")
		)
		(fp_line
			(start 0.7874 -0.4064)
			(end -0.7874 -0.4064)
			(stroke
				(width 0.1524)
				(type default)
			)
			(layer "B.SilkS")
		)
		(fp_line
			(start 0.7874 0.4064)
			(end 0.7874 -0.4064)
			(stroke
				(width 0.1524)
				(type default)
			)
			(layer "B.SilkS")
		)
		(fp_line
			(start -0.67945 -0.3048)
			(end -0.67945 0.3048)
			(stroke
				(width 0.1)
				(type default)
			)
			(layer "B.Fab")
		)
		(fp_line
			(start -0.67945 0.3048)
			(end -0.120396 0.3048)
			(stroke
				(width 0.1)
				(type default)
			)
			(layer "B.Fab")
		)
		(fp_line
			(start -0.12065 -0.3048)
			(end -0.67945 -0.3048)
			(stroke
				(width 0.1)
				(type default)
			)
			(layer "B.Fab")
		)
		(fp_line
			(start -0.12065 -0.2794)
			(end -0.12065 -0.3048)
			(stroke
				(width 0.1)
				(type default)
			)
			(layer "B.Fab")
		)
		(fp_line
			(start -0.120396 0.2794)
			(end 0.12065 0.2794)
			(stroke
				(width 0.1)
				(type default)
			)
			(layer "B.Fab")
		)
		(fp_line
			(start -0.120396 0.3048)
			(end -0.120396 0.2794)
			(stroke
				(width 0.1)
				(type default)
			)
			(layer "B.Fab")
		)
		(fp_line
			(start 0.12065 -0.305054)
			(end 0.12065 -0.2794)
			(stroke
				(width 0.1)
				(type default)
			)
			(layer "B.Fab")
		)
		(fp_line
			(start 0.12065 -0.2794)
			(end -0.12065 -0.2794)
			(stroke
				(width 0.1)
				(type default)
			)
			(layer "B.Fab")
		)
		(fp_line
			(start 0.12065 0.2794)
			(end 0.12065 0.3048)
			(stroke
				(width 0.1)
				(type default)
			)
			(layer "B.Fab")
		)
		(fp_line
			(start 0.12065 0.3048)
			(end 0.67945 0.3048)
			(stroke
				(width 0.1)
				(type default)
			)
			(layer "B.Fab")
		)
		(fp_line
			(start 0.67945 -0.305054)
			(end 0.12065 -0.305054)
			(stroke
				(width 0.1)
				(type default)
			)
			(layer "B.Fab")
		)
		(fp_line
			(start 0.67945 0.3048)
			(end 0.67945 -0.305054)
			(stroke
				(width 0.1)
				(type default)
			)
			(layer "B.Fab")
		)
		(pad "1" smd circle
			(at 0.40005 0 180)
			(size 0 0)
			(layers "B.Cu" "B.Mask" "B.Paste")
			(net "P12V_AUX")
		)
		(pad "2" smd circle
			(at -0.40005 0 180)
			(size 0 0)
			(layers "B.Cu" "B.Mask" "B.Paste")
			(net "GND")
		)
	)
)
